# T6G (Grand Teton) — schematic netlist excerpt (pin names and nets, part order shuffled) for the footprints in the layout excerpt that follows; sources: Cadence DE-HDL packaged netlist, KiCad conversion of 04192023_DAF0TMB3IC0_F0TG_MB_C_brd_V02_OCP.brd

U7  74CBTLV3126PW  IC  pkg TSSOP14  page 132
  \1oe\  = FB_BMC_ISOLATE
  \1a\  = NCSI_BMC_TXD1_R
  \1b\  = NCSI_OCP_SFF_TXD1
  \2oe\  = FB_BMC_ISOLATE
  \2a\  = NCSI_BMC_TXD0_R
  \2b\  = NCSI_OCP_SFF_TXD0
  GND  = GND
  \3b\  = NCSI_OCP_SFF_TX_EN
  \3a\  = NCSI_BMC_TX_EN_R
  \3oe\  = FB_BMC_ISOLATE
  \4b\  = OCP_SFF_ISO2_RBT_ARB_OUT
  \4a\  = OCP_SFF_RBT_ARB_OUT
  \4oe\  = FB_BMC_ISOLATE
  VCC  = P3V3_AUX

C2625  Q_CAP  22UF 4V 20% X6S  pkg C0402  page 70 : A = PVDDIO_P0 ; B = GND

(kicad_pcb
	(version 20260206)
	(generator "pcbnew")
	(generator_version "10.0")
	(general
		(thickness 1.6)
		(legacy_teardrops no)
	)
	(paper "A4")
	(title_block
		(title "04192023_DAF0TMB3IC0_F0TG_MB_C_brd_V02_OCP.brd")
		(comment 1 "Grand Teton / footprints 5357-5358 of 8354")
	)
	(layers
		(0 "F.Cu" signal "TOP")
		(4 "In1.Cu" signal "GND")
		(6 "In2.Cu" signal "IN1")
		(8 "In3.Cu" signal "GND1")
		(10 "In4.Cu" signal "IN2")
		(12 "In5.Cu" signal "GND2")
		(14 "In6.Cu" signal "IN3")
		(16 "In7.Cu" signal "GND3")
		(18 "In8.Cu" signal "VCC")
		(20 "In9.Cu" signal "VCC1")
		(22 "In10.Cu" signal "GND4")
		(24 "In11.Cu" signal "IN4")
		(26 "In12.Cu" signal "GND5")
		(28 "In13.Cu" signal "IN5")
		(30 "In14.Cu" signal "GND6")
		(32 "In15.Cu" signal "IN6")
		(34 "In16.Cu" signal "GND7")
		(2 "B.Cu" signal "BOTTOM")
		(9 "F.Adhes" user "F.Adhesive")
		(11 "B.Adhes" user "B.Adhesive")
		(13 "F.Paste" user "Package Geometry/Pastemask Top")
		(15 "B.Paste" user "Package Geometry/Pastemask Bottom")
		(5 "F.SilkS" user "Ref Des/Silkscreen Top")
		(7 "B.SilkS" user "Ref Des/Silkscreen Bottom")
		(1 "F.Mask" user "Board Geometry/Soldermask Top")
		(3 "B.Mask" user "Board Geometry/Soldermask Bottom")
		(17 "Dwgs.User" user "User.Drawings")
		(19 "Cmts.User" user "User.Comments")
		(21 "Eco1.User" user "User.Eco1")
		(23 "Eco2.User" user "User.Eco2")
		(25 "Edge.Cuts" user "Board Geometry/Outline")
		(27 "Margin" user)
		(31 "F.CrtYd" user "Package Geometry/Place Bound Top")
		(29 "B.CrtYd" user "Package Geometry/Place Bound Bottom")
		(35 "F.Fab" user "Ref Des/Assembly Top")
		(33 "B.Fab" user "Ref Des/Assembly Bottom")
	)
	(footprint ""
		(layer "B.Cu")
		(at 210.83905 -69.530468)
		(property "Reference" "U7"
			(at 2.032 -3.27533 0)
			(unlocked yes)
			(layer "B.SilkS")
			(effects
				(font
					(size 0.7874 0.5842)
					(thickness 0.1524)
				)
				(justify left mirror)
			)
		)
		(property "Value" ""
			(at 0 0 0)
			(layer "B.Fab")
			(effects
				(font
					(size 1.27 1.27)
				)
				(justify mirror)
			)
		)
		(duplicate_pad_numbers_are_jumpers no)
		(fp_line
			(start -2.0066 -2.5527)
			(end -2.0066 2.5527)
			(stroke
				(width 0.1524)
				(type default)
			)
			(layer "B.SilkS")
		)
		(fp_line
			(start -2.0066 2.5527)
			(end 2.0066 2.5527)
			(stroke
				(width 0.1524)
				(type default)
			)
			(layer "B.SilkS")
		)
		(fp_line
			(start -0.5715 -2.5527)
			(end -2.0066 -2.5527)
			(stroke
				(width 0.1524)
				(type default)
			)
			(layer "B.SilkS")
		)
		(fp_line
			(start 0 -1.9812)
			(end -0.5715 -2.5527)
			(stroke
				(width 0.1524)
				(type default)
			)
			(layer "B.SilkS")
		)
		(fp_line
			(start 0.5715 -2.5527)
			(end 0 -1.9812)
			(stroke
				(width 0.1524)
				(type default)
			)
			(layer "B.SilkS")
		)
		(fp_line
			(start 2.0066 -2.5527)
			(end 0.5715 -2.5527)
			(stroke
				(width 0.1524)
				(type default)
			)
			(layer "B.SilkS")
		)
		(fp_line
			(start 2.0066 2.5527)
			(end 2.0066 -2.5527)
			(stroke
				(width 0.1524)
				(type default)
			)
			(layer "B.SilkS")
		)
		(fp_poly
			(pts
				(xy 3.179318 -2.37617) (xy 2.893822 -2.953258) (xy 3.516884 -2.906014)
			)
			(stroke
				(width 0)
				(type default)
			)
			(fill yes)
			(layer "B.SilkS")
		)
		(fp_line
			(start -2.249932 -2.549906)
			(end -2.249932 2.549906)
			(stroke
				(width 0.1)
				(type default)
			)
			(layer "B.Fab")
		)
		(fp_line
			(start -2.249932 2.549906)
			(end 2.249932 2.549906)
			(stroke
				(width 0.1)
				(type default)
			)
			(layer "B.Fab")
		)
		(fp_line
			(start 2.249932 -2.549906)
			(end -2.249932 -2.549906)
			(stroke
				(width 0.1)
				(type default)
			)
			(layer "B.Fab")
		)
		(fp_line
			(start 2.249932 2.549906)
			(end 2.249932 -2.549906)
			(stroke
				(width 0.1)
				(type default)
			)
			(layer "B.Fab")
		)
		(fp_poly
			(pts
				(xy 4.36372 -1.608328) (xy 4.36372 -2.233168) (xy 3.81 -1.905)
			)
			(stroke
				(width 0)
				(type default)
			)
			(fill yes)
			(layer "B.Fab")
		)
		(pad "1" smd rect
			(at 2.921 -1.949958 270)
			(size 0.3556 1.4986)
			(layers "B.Cu" "B.Mask" "B.Paste")
			(net "FB_BMC_ISOLATE")
		)
		(pad "2" smd rect
			(at 2.921 -1.299972 270)
			(size 0.3556 1.4986)
			(layers "B.Cu" "B.Mask" "B.Paste")
			(net "NCSI_BMC_TXD1_R")
		)
		(pad "3" smd rect
			(at 2.921 -0.649986 270)
			(size 0.3556 1.4986)
			(layers "B.Cu" "B.Mask" "B.Paste")
			(net "NCSI_OCP_SFF_TXD1")
		)
		(pad "4" smd rect
			(at 2.921 0 270)
			(size 0.3556 1.4986)
			(layers "B.Cu" "B.Mask" "B.Paste")
			(net "FB_BMC_ISOLATE")
		)
		(pad "5" smd rect
			(at 2.921 0.649986 270)
			(size 0.3556 1.4986)
			(layers "B.Cu" "B.Mask" "B.Paste")
			(net "NCSI_BMC_TXD0_R")
		)
		(pad "6" smd rect
			(at 2.921 1.299972 270)
			(size 0.3556 1.4986)
			(layers "B.Cu" "B.Mask" "B.Paste")
			(net "NCSI_OCP_SFF_TXD0")
		)
		(pad "7" smd rect
			(at 2.921 1.949958 270)
			(size 0.3556 1.4986)
			(layers "B.Cu" "B.Mask" "B.Paste")
			(net "GND")
		)
		(pad "8" smd rect
			(at -2.921 1.949958 270)
			(size 0.3556 1.4986)
			(layers "B.Cu" "B.Mask" "B.Paste")
			(net "NCSI_OCP_SFF_TX_EN")
		)
		(pad "9" smd rect
			(at -2.921 1.299972 270)
			(size 0.3556 1.4986)
			(layers "B.Cu" "B.Mask" "B.Paste")
			(net "NCSI_BMC_TX_EN_R")
		)
		(pad "10" smd rect
			(at -2.921 0.649986 270)
			(size 0.3556 1.4986)
			(layers "B.Cu" "B.Mask" "B.Paste")
			(net "FB_BMC_ISOLATE")
		)
		(pad "11" smd rect
			(at -2.921 0 270)
			(size 0.3556 1.4986)
			(layers "B.Cu" "B.Mask" "B.Paste")
			(net "OCP_SFF_ISO2_RBT_ARB_OUT")
		)
		(pad "12" smd rect
			(at -2.921 -0.649986 270)
			(size 0.3556 1.4986)
			(layers "B.Cu" "B.Mask" "B.Paste")
			(net "OCP_SFF_RBT_ARB_OUT")
		)
		(pad "13" smd rect
			(at -2.921 -1.299972 270)
			(size 0.3556 1.4986)
			(layers "B.Cu" "B.Mask" "B.Paste")
			(net "FB_BMC_ISOLATE")
		)
		(pad "14" smd rect
			(at -2.921 -1.949958 270)
			(size 0.3556 1.4986)
			(layers "B.Cu" "B.Mask" "B.Paste")
			(net "P3V3_AUX")
		)
	)
	(footprint ""
		(layer "B.Cu")
		(at 346.532454 -256.73431 180)
		(property "Reference" "C2625"
			(at 0 0 0)
			(layer "B.SilkS")
			(hide yes)
			(effects
				(font
					(size 1.27 1.27)
				)
				(justify mirror)
			)
		)
		(property "Value" ""
			(at 0 0 0)
			(layer "B.Fab")
			(effects
				(font
					(size 1.27 1.27)
				)
				(justify mirror)
			)
		)
		(duplicate_pad_numbers_are_jumpers no)
		(fp_line
			(start 0.7874 0.4064)
			(end 0.7874 -0.4064)
			(stroke
				(width 0.1524)
				(type default)
			)
			(layer "B.SilkS")
		)
		(fp_line
			(start 0.7874 -0.4064)
			(end -0.7874 -0.4064)
			(stroke
				(width 0.1524)
				(type default)
			)
			(layer "B.SilkS")
		)
		(fp_line
			(start -0.7874 0.4064)
			(end 0.7874 0.4064)
			(stroke
				(width 0.1524)
				(type default)
			)
			(layer "B.SilkS")
		)
		(fp_line
			(start -0.7874 -0.4064)
			(end -0.7874 0.4064)
			(stroke
				(width 0.1524)
				(type default)
			)
			(layer "B.SilkS")
		)
		(fp_line
			(start 0.67945 0.3048)
			(end 0.67945 -0.305054)
			(stroke
				(width 0.1)
				(type default)
			)
			(layer "B.Fab")
		)
		(fp_line
			(start 0.67945 -0.305054)
			(end 0.12065 -0.305054)
			(stroke
				(width 0.1)
				(type default)
			)
			(layer "B.Fab")
		)
		(fp_line
			(start 0.12065 0.3048)
			(end 0.67945 0.3048)
			(stroke
				(width 0.1)
				(type default)
			)
			(layer "B.Fab")
		)
		(fp_line
			(start 0.12065 0.2794)
			(end 0.12065 0.3048)
			(stroke
				(width 0.1)
				(type default)
			)
			(layer "B.Fab")
		)
		(fp_line
			(start 0.12065 -0.2794)
			(end -0.12065 -0.2794)
			(stroke
				(width 0.1)
				(type default)
			)
			(layer "B.Fab")
		)
		(fp_line
			(start 0.12065 -0.305054)
			(end 0.12065 -0.2794)
			(stroke
				(width 0.1)
				(type default)
			)
			(layer "B.Fab")
		)
		(fp_line
			(start -0.120396 0.3048)
			(end -0.120396 0.2794)
			(stroke
				(width 0.1)
				(type default)
			)
			(layer "B.Fab")
		)
		(fp_line
			(start -0.120396 0.2794)
			(end 0.12065 0.2794)
			(stroke
				(width 0.1)
				(type default)
			)
			(layer "B.Fab")
		)
		(fp_line
			(start -0.12065 -0.2794)
			(end -0.12065 -0.3048)
			(stroke
				(width 0.1)
				(type default)
			)
			(layer "B.Fab")
		)
		(fp_line
			(start -0.12065 -0.3048)
			(end -0.67945 -0.3048)
			(stroke
				(width 0.1)
				(type default)
			)
			(layer "B.Fab")
		)
		(fp_line
			(start -0.67945 0.3048)
			(end -0.120396 0.3048)
			(stroke
				(width 0.1)
				(type default)
			)
			(layer "B.Fab")
		)
		(fp_line
			(start -0.67945 -0.3048)
			(end -0.67945 0.3048)
			(stroke
				(width 0.1)
				(type default)
			)
			(layer "B.Fab")
		)
		(pad "1" smd circle
			(at 0.40005 0)
			(size 0 0)
			(layers "B.Cu" "B.Mask" "B.Paste")
			(net "PVDDIO_P0")
		)
		(pad "2" smd circle
			(at -0.40005 0)
			(size 0 0)
			(layers "B.Cu" "B.Mask" "B.Paste")
			(net "GND")
		)
	)
)
